# T6G (Grand Teton) — schematic netlist excerpt (pin names and nets, part order shuffled) for the footprints in the layout excerpt that follows; sources: Cadence DE-HDL packaged netlist, KiCad conversion of 04192023_DAF0TMB3IC0_F0TG_MB_C_brd_V02_OCP.brd

C357  Q_CAP  0.1UF 16V 10% X7R  pkg C0402  page 83 : A = P3V3_AUX ; B = GND
C6536  Q_CAP_DIFFBUS  DIFF BUS_0.22UF 6.3V 20% X6S  pkg C0201  page 286 : \1\ = P5E_CPU0_P1_TX_BUF_C_DN<1> ; \2\ = P5E_CPU0_P1_TX_BUF_DN<1>
C210  Q_CAP  0.001UF 50V 10% EMPTY  pkg C0402  page 27 : A = JTAG_CPU0_TCK ; B = GND

(kicad_pcb
	(version 20260206)
	(generator "pcbnew")
	(generator_version "10.0")
	(general
		(thickness 1.6)
		(legacy_teardrops no)
	)
	(paper "A4")
	(title_block
		(title "04192023_DAF0TMB3IC0_F0TG_MB_C_brd_V02_OCP.brd")
		(comment 1 "Grand Teton / footprints 5902-5904 of 8354")
	)
	(layers
		(0 "F.Cu" signal "TOP")
		(4 "In1.Cu" signal "GND")
		(6 "In2.Cu" signal "IN1")
		(8 "In3.Cu" signal "GND1")
		(10 "In4.Cu" signal "IN2")
		(12 "In5.Cu" signal "GND2")
		(14 "In6.Cu" signal "IN3")
		(16 "In7.Cu" signal "GND3")
		(18 "In8.Cu" signal "VCC")
		(20 "In9.Cu" signal "VCC1")
		(22 "In10.Cu" signal "GND4")
		(24 "In11.Cu" signal "IN4")
		(26 "In12.Cu" signal "GND5")
		(28 "In13.Cu" signal "IN5")
		(30 "In14.Cu" signal "GND6")
		(32 "In15.Cu" signal "IN6")
		(34 "In16.Cu" signal "GND7")
		(2 "B.Cu" signal "BOTTOM")
		(9 "F.Adhes" user "F.Adhesive")
		(11 "B.Adhes" user "B.Adhesive")
		(13 "F.Paste" user "Package Geometry/Pastemask Top")
		(15 "B.Paste" user "Package Geometry/Pastemask Bottom")
		(5 "F.SilkS" user "Ref Des/Silkscreen Top")
		(7 "B.SilkS" user "Ref Des/Silkscreen Bottom")
		(1 "F.Mask" user "Board Geometry/Soldermask Top")
		(3 "B.Mask" user "Board Geometry/Soldermask Bottom")
		(17 "Dwgs.User" user "User.Drawings")
		(19 "Cmts.User" user "User.Comments")
		(21 "Eco1.User" user "User.Eco1")
		(23 "Eco2.User" user "User.Eco2")
		(25 "Edge.Cuts" user "Board Geometry/Outline")
		(27 "Margin" user)
		(31 "F.CrtYd" user "Package Geometry/Place Bound Top")
		(29 "B.CrtYd" user "Package Geometry/Place Bound Bottom")
		(35 "F.Fab" user "Ref Des/Assembly Top")
		(33 "B.Fab" user "Ref Des/Assembly Bottom")
	)
	(footprint ""
		(layer "B.Cu")
		(at 182.332376 -113.862866 180)
		(property "Reference" "C357"
			(at 0 0 0)
			(layer "B.SilkS")
			(hide yes)
			(effects
				(font
					(size 1.27 1.27)
				)
				(justify mirror)
			)
		)
		(property "Value" ""
			(at 0 0 0)
			(layer "B.Fab")
			(effects
				(font
					(size 1.27 1.27)
				)
				(justify mirror)
			)
		)
		(duplicate_pad_numbers_are_jumpers no)
		(fp_line
			(start 0.69215 0.2921)
			(end 0.69215 -0.2921)
			(stroke
				(width 0.1524)
				(type default)
			)
			(layer "B.SilkS")
		)
		(fp_line
			(start 0.69215 -0.2921)
			(end -0.69215 -0.2921)
			(stroke
				(width 0.1524)
				(type default)
			)
			(layer "B.SilkS")
		)
		(fp_line
			(start -0.69215 0.2921)
			(end 0.69215 0.2921)
			(stroke
				(width 0.1524)
				(type default)
			)
			(layer "B.SilkS")
		)
		(fp_line
			(start -0.69215 -0.2921)
			(end -0.69215 0.2921)
			(stroke
				(width 0.1524)
				(type default)
			)
			(layer "B.SilkS")
		)
		(fp_line
			(start 0.51435 0.2794)
			(end 0.51435 -0.2794)
			(stroke
				(width 0.1)
				(type default)
			)
			(layer "B.Fab")
		)
		(fp_line
			(start 0.51435 -0.2794)
			(end -0.51435 -0.2794)
			(stroke
				(width 0.1)
				(type default)
			)
			(layer "B.Fab")
		)
		(fp_line
			(start -0.51435 0.2794)
			(end 0.51435 0.2794)
			(stroke
				(width 0.1)
				(type default)
			)
			(layer "B.Fab")
		)
		(fp_line
			(start -0.51435 -0.2794)
			(end -0.51435 0.2794)
			(stroke
				(width 0.1)
				(type default)
			)
			(layer "B.Fab")
		)
		(pad "1" smd circle
			(at 0.40005 0)
			(size 0 0)
			(layers "B.Cu" "B.Mask" "B.Paste")
			(net "P3V3_AUX")
		)
		(pad "2" smd circle
			(at -0.40005 0)
			(size 0 0)
			(layers "B.Cu" "B.Mask" "B.Paste")
			(net "GND")
		)
		(zone
			(layer "B.Cu")
			(hatch none 0.5)
			(connect_pads
				(clearance 0)
			)
			(min_thickness 0.25)
			(keepout
				(tracks not_allowed)
				(vias allowed)
				(pads allowed)
				(copperpour not_allowed)
				(footprints allowed)
			)
			(placement
				(enabled no)
				(sheetname "")
			)
			(fill
				(thermal_gap 0.5)
				(thermal_bridge_width 0.5)
				(island_removal_mode 0)
			)
			(polygon
				(pts
					(xy 182.141876 -113.774982) (xy 182.141876 -113.950496) (xy 182.233316 -114.008662) (xy 182.432706 -114.008662)
					(xy 182.522876 -113.950496) (xy 182.522876 -113.775236) (xy 182.432706 -113.716816) (xy 182.233316 -113.716816)
				)
			)
		)
	)
	(footprint ""
		(layer "B.Cu")
		(at 308.363366 -416.899344 90)
		(property "Reference" "C6536"
			(at 0 0 90)
			(layer "B.SilkS")
			(hide yes)
			(effects
				(font
					(size 1.27 1.27)
				)
				(justify mirror)
			)
		)
		(property "Value" ""
			(at 0 0 90)
			(layer "B.Fab")
			(effects
				(font
					(size 1.27 1.27)
				)
				(justify mirror)
			)
		)
		(duplicate_pad_numbers_are_jumpers no)
		(fp_line
			(start 0.299974 -0.150114)
			(end -0.299974 -0.150114)
			(stroke
				(width 0.1)
				(type default)
			)
			(layer "B.Fab")
		)
		(fp_line
			(start -0.299974 -0.150114)
			(end -0.299974 0.150114)
			(stroke
				(width 0.1)
				(type default)
			)
			(layer "B.Fab")
		)
		(fp_line
			(start 0.299974 0.150114)
			(end 0.299974 -0.150114)
			(stroke
				(width 0.1)
				(type default)
			)
			(layer "B.Fab")
		)
		(fp_line
			(start -0.299974 0.150114)
			(end 0.299974 0.150114)
			(stroke
				(width 0.1)
				(type default)
			)
			(layer "B.Fab")
		)
		(pad "1" smd rect
			(at 0.2667 0 270)
			(size 0.3048 0.381)
			(layers "B.Cu" "B.Mask" "B.Paste")
			(net "P5E_CPU0_P1_TX_BUF_C_DN<1>")
		)
		(pad "2" smd rect
			(at -0.2667 0 270)
			(size 0.3048 0.381)
			(layers "B.Cu" "B.Mask" "B.Paste")
			(net "P5E_CPU0_P1_TX_BUF_DN<1>")
		)
	)
	(footprint ""
		(layer "B.Cu")
		(at 376.472958 -208.530952 90)
		(property "Reference" "C210"
			(at 0 0 90)
			(layer "B.SilkS")
			(hide yes)
			(effects
				(font
					(size 1.27 1.27)
				)
				(justify mirror)
			)
		)
		(property "Value" ""
			(at 0 0 90)
			(layer "B.Fab")
			(effects
				(font
					(size 1.27 1.27)
				)
				(justify mirror)
			)
		)
		(duplicate_pad_numbers_are_jumpers no)
		(fp_line
			(start 0.7874 -0.4064)
			(end -0.7874 -0.4064)
			(stroke
				(width 0.1524)
				(type default)
			)
			(layer "B.SilkS")
		)
		(fp_line
			(start -0.7874 -0.4064)
			(end -0.7874 0.4064)
			(stroke
				(width 0.1524)
				(type default)
			)
			(layer "B.SilkS")
		)
		(fp_line
			(start 0.7874 0.4064)
			(end 0.7874 -0.4064)
			(stroke
				(width 0.1524)
				(type default)
			)
			(layer "B.SilkS")
		)
		(fp_line
			(start -0.7874 0.4064)
			(end 0.7874 0.4064)
			(stroke
				(width 0.1524)
				(type default)
			)
			(layer "B.SilkS")
		)
		(fp_line
			(start 0.67945 -0.305054)
			(end 0.12065 -0.305054)
			(stroke
				(width 0.1)
				(type default)
			)
			(layer "B.Fab")
		)
		(fp_line
			(start 0.12065 -0.305054)
			(end 0.12065 -0.2794)
			(stroke
				(width 0.1)
				(type default)
			)
			(layer "B.Fab")
		)
		(fp_line
			(start -0.12065 -0.3048)
			(end -0.67945 -0.3048)
			(stroke
				(width 0.1)
				(type default)
			)
			(layer "B.Fab")
		)
		(fp_line
			(start -0.67945 -0.3048)
			(end -0.67945 0.3048)
			(stroke
				(width 0.1)
				(type default)
			)
			(layer "B.Fab")
		)
		(fp_line
			(start 0.12065 -0.2794)
			(end -0.12065 -0.2794)
			(stroke
				(width 0.1)
				(type default)
			)
			(layer "B.Fab")
		)
		(fp_line
			(start -0.12065 -0.2794)
			(end -0.12065 -0.3048)
			(stroke
				(width 0.1)
				(type default)
			)
			(layer "B.Fab")
		)
		(fp_line
			(start 0.12065 0.2794)
			(end 0.12065 0.3048)
			(stroke
				(width 0.1)
				(type default)
			)
			(layer "B.Fab")
		)
		(fp_line
			(start -0.120396 0.2794)
			(end 0.12065 0.2794)
			(stroke
				(width 0.1)
				(type default)
			)
			(layer "B.Fab")
		)
		(fp_line
			(start 0.67945 0.3048)
			(end 0.67945 -0.305054)
			(stroke
				(width 0.1)
				(type default)
			)
			(layer "B.Fab")
		)
		(fp_line
			(start 0.12065 0.3048)
			(end 0.67945 0.3048)
			(stroke
				(width 0.1)
				(type default)
			)
			(layer "B.Fab")
		)
		(fp_line
			(start -0.120396 0.3048)
			(end -0.120396 0.2794)
			(stroke
				(width 0.1)
				(type default)
			)
			(layer "B.Fab")
		)
		(fp_line
			(start -0.67945 0.3048)
			(end -0.120396 0.3048)
			(stroke
				(width 0.1)
				(type default)
			)
			(layer "B.Fab")
		)
		(pad "1" smd circle
			(at 0.40005 0 270)
			(size 0 0)
			(layers "B.Cu" "B.Mask" "B.Paste")
			(net "JTAG_CPU0_TCK")
		)
		(pad "2" smd circle
			(at -0.40005 0 270)
			(size 0 0)
			(layers "B.Cu" "B.Mask" "B.Paste")
			(net "GND")
		)
	)
)
